# T6G (Grand Teton) — schematic netlist excerpt (pin names and nets, part order shuffled) for the footprints in the layout excerpt that follows; sources: Cadence DE-HDL packaged netlist, KiCad conversion of 04192023_DAF0TMB3IC0_F0TG_MB_C_brd_V02_OCP.brd

L1  Q_INDUCTOR  FCM2012KF-601T/0.5A IND  pkg SMLF  page 183 : \1\ = P3V3_AUX ; \2\ = P3V3_9ZXL045_P1
C2010  Q_CAP  0.1UF 25V 10% X7R  pkg 0402  page 235 : A = P3V3_AUX ; B = GND
C6575  Q_CAP_DIFFBUS  DIFF BUS_0.22UF 6.3V 20% X6S  pkg C0201  page 297 : \1\ = P5E_CPU0_P2_TX_BUF_C_DP<5> ; \2\ = P5E_CPU0_P2_TX_BUF_DP<5>
C1557  Q_CAP_DIFFBUS  DIFF BUS_0.22UF 6.3V 20% X6S  pkg C0201  page 65 : \1\ = P5E_CPU0_G3_TX_C_DP<11> ; \2\ = P5E_CPU0_G3_TX_DP<11>

(kicad_pcb
	(version 20260206)
	(generator "pcbnew")
	(generator_version "10.0")
	(general
		(thickness 1.6)
		(legacy_teardrops no)
	)
	(paper "A4")
	(title_block
		(title "04192023_DAF0TMB3IC0_F0TG_MB_C_brd_V02_OCP.brd")
		(comment 1 "Grand Teton / footprints 3926-3929 of 8354")
	)
	(layers
		(0 "F.Cu" signal "TOP")
		(4 "In1.Cu" signal "GND")
		(6 "In2.Cu" signal "IN1")
		(8 "In3.Cu" signal "GND1")
		(10 "In4.Cu" signal "IN2")
		(12 "In5.Cu" signal "GND2")
		(14 "In6.Cu" signal "IN3")
		(16 "In7.Cu" signal "GND3")
		(18 "In8.Cu" signal "VCC")
		(20 "In9.Cu" signal "VCC1")
		(22 "In10.Cu" signal "GND4")
		(24 "In11.Cu" signal "IN4")
		(26 "In12.Cu" signal "GND5")
		(28 "In13.Cu" signal "IN5")
		(30 "In14.Cu" signal "GND6")
		(32 "In15.Cu" signal "IN6")
		(34 "In16.Cu" signal "GND7")
		(2 "B.Cu" signal "BOTTOM")
		(9 "F.Adhes" user "F.Adhesive")
		(11 "B.Adhes" user "B.Adhesive")
		(13 "F.Paste" user "Package Geometry/Pastemask Top")
		(15 "B.Paste" user "Package Geometry/Pastemask Bottom")
		(5 "F.SilkS" user "Ref Des/Silkscreen Top")
		(7 "B.SilkS" user "Ref Des/Silkscreen Bottom")
		(1 "F.Mask" user "Board Geometry/Soldermask Top")
		(3 "B.Mask" user "Board Geometry/Soldermask Bottom")
		(17 "Dwgs.User" user "User.Drawings")
		(19 "Cmts.User" user "User.Comments")
		(21 "Eco1.User" user "User.Eco1")
		(23 "Eco2.User" user "User.Eco2")
		(25 "Edge.Cuts" user "Board Geometry/Outline")
		(27 "Margin" user)
		(31 "F.CrtYd" user "Package Geometry/Place Bound Top")
		(29 "B.CrtYd" user "Package Geometry/Place Bound Bottom")
		(35 "F.Fab" user "Ref Des/Assembly Top")
		(33 "B.Fab" user "Ref Des/Assembly Bottom")
	)
	(footprint ""
		(layer "F.Cu")
		(at 366.415066 -424.002962 90)
		(property "Reference" "C2010"
			(at 0 0 90)
			(layer "F.SilkS")
			(hide yes)
			(effects
				(font
					(size 1.27 1.27)
				)
			)
		)
		(property "Value" ""
			(at 0 0 90)
			(layer "F.Fab")
			(effects
				(font
					(size 1.27 1.27)
				)
			)
		)
		(duplicate_pad_numbers_are_jumpers no)
		(fp_line
			(start 0.7874 -0.4064)
			(end 0.7874 0.4064)
			(stroke
				(width 0.1524)
				(type default)
			)
			(layer "F.SilkS")
		)
		(fp_line
			(start -0.7874 -0.4064)
			(end 0.7874 -0.4064)
			(stroke
				(width 0.1524)
				(type default)
			)
			(layer "F.SilkS")
		)
		(fp_line
			(start 0.7874 0.4064)
			(end -0.7874 0.4064)
			(stroke
				(width 0.1524)
				(type default)
			)
			(layer "F.SilkS")
		)
		(fp_line
			(start -0.7874 0.4064)
			(end -0.7874 -0.4064)
			(stroke
				(width 0.1524)
				(type default)
			)
			(layer "F.SilkS")
		)
		(fp_line
			(start -0.12065 -0.305054)
			(end -0.12065 -0.2794)
			(stroke
				(width 0.1)
				(type default)
			)
			(layer "F.Fab")
		)
		(fp_line
			(start -0.67945 -0.305054)
			(end -0.12065 -0.305054)
			(stroke
				(width 0.1)
				(type default)
			)
			(layer "F.Fab")
		)
		(fp_line
			(start 0.67945 -0.3048)
			(end 0.67945 0.3048)
			(stroke
				(width 0.1)
				(type default)
			)
			(layer "F.Fab")
		)
		(fp_line
			(start 0.12065 -0.3048)
			(end 0.67945 -0.3048)
			(stroke
				(width 0.1)
				(type default)
			)
			(layer "F.Fab")
		)
		(fp_line
			(start 0.12065 -0.2794)
			(end 0.12065 -0.3048)
			(stroke
				(width 0.1)
				(type default)
			)
			(layer "F.Fab")
		)
		(fp_line
			(start -0.12065 -0.2794)
			(end 0.12065 -0.2794)
			(stroke
				(width 0.1)
				(type default)
			)
			(layer "F.Fab")
		)
		(fp_line
			(start 0.120396 0.2794)
			(end -0.12065 0.2794)
			(stroke
				(width 0.1)
				(type default)
			)
			(layer "F.Fab")
		)
		(fp_line
			(start -0.12065 0.2794)
			(end -0.12065 0.3048)
			(stroke
				(width 0.1)
				(type default)
			)
			(layer "F.Fab")
		)
		(fp_line
			(start 0.67945 0.3048)
			(end 0.120396 0.3048)
			(stroke
				(width 0.1)
				(type default)
			)
			(layer "F.Fab")
		)
		(fp_line
			(start 0.120396 0.3048)
			(end 0.120396 0.2794)
			(stroke
				(width 0.1)
				(type default)
			)
			(layer "F.Fab")
		)
		(fp_line
			(start -0.12065 0.3048)
			(end -0.67945 0.3048)
			(stroke
				(width 0.1)
				(type default)
			)
			(layer "F.Fab")
		)
		(fp_line
			(start -0.67945 0.3048)
			(end -0.67945 -0.305054)
			(stroke
				(width 0.1)
				(type default)
			)
			(layer "F.Fab")
		)
		(pad "1" smd circle
			(at -0.40005 0 90)
			(size 0 0)
			(layers "F.Cu" "F.Mask" "F.Paste")
			(net "P3V3_AUX")
		)
		(pad "2" smd circle
			(at 0.40005 0 90)
			(size 0 0)
			(layers "F.Cu" "F.Mask" "F.Paste")
			(net "GND")
		)
	)
	(footprint ""
		(layer "F.Cu")
		(at 387.099302 -416.899344 -90)
		(property "Reference" "C6575"
			(at 0 0 270)
			(layer "F.SilkS")
			(hide yes)
			(effects
				(font
					(size 1.27 1.27)
				)
			)
		)
		(property "Value" ""
			(at 0 0 270)
			(layer "F.Fab")
			(effects
				(font
					(size 1.27 1.27)
				)
			)
		)
		(duplicate_pad_numbers_are_jumpers no)
		(fp_line
			(start -0.299974 0.150114)
			(end -0.299974 -0.150114)
			(stroke
				(width 0.1)
				(type default)
			)
			(layer "F.Fab")
		)
		(fp_line
			(start 0.299974 0.150114)
			(end -0.299974 0.150114)
			(stroke
				(width 0.1)
				(type default)
			)
			(layer "F.Fab")
		)
		(fp_line
			(start -0.299974 -0.150114)
			(end 0.299974 -0.150114)
			(stroke
				(width 0.1)
				(type default)
			)
			(layer "F.Fab")
		)
		(fp_line
			(start 0.299974 -0.150114)
			(end 0.299974 0.150114)
			(stroke
				(width 0.1)
				(type default)
			)
			(layer "F.Fab")
		)
		(pad "1" smd rect
			(at -0.2667 0 270)
			(size 0.3048 0.381)
			(layers "F.Cu" "F.Mask" "F.Paste")
			(net "P5E_CPU0_P2_TX_BUF_C_DP<5>")
		)
		(pad "2" smd rect
			(at 0.2667 0 270)
			(size 0.3048 0.381)
			(layers "F.Cu" "F.Mask" "F.Paste")
			(net "P5E_CPU0_P2_TX_BUF_DP<5>")
		)
	)
	(footprint ""
		(layer "F.Cu")
		(at 402.097748 -16.100298 90)
		(property "Reference" "C1557"
			(at 0 0 90)
			(layer "F.SilkS")
			(hide yes)
			(effects
				(font
					(size 1.27 1.27)
				)
			)
		)
		(property "Value" ""
			(at 0 0 90)
			(layer "F.Fab")
			(effects
				(font
					(size 1.27 1.27)
				)
			)
		)
		(duplicate_pad_numbers_are_jumpers no)
		(fp_line
			(start 0.299974 -0.150114)
			(end 0.299974 0.150114)
			(stroke
				(width 0.1)
				(type default)
			)
			(layer "F.Fab")
		)
		(fp_line
			(start -0.299974 -0.150114)
			(end 0.299974 -0.150114)
			(stroke
				(width 0.1)
				(type default)
			)
			(layer "F.Fab")
		)
		(fp_line
			(start 0.299974 0.150114)
			(end -0.299974 0.150114)
			(stroke
				(width 0.1)
				(type default)
			)
			(layer "F.Fab")
		)
		(fp_line
			(start -0.299974 0.150114)
			(end -0.299974 -0.150114)
			(stroke
				(width 0.1)
				(type default)
			)
			(layer "F.Fab")
		)
		(pad "1" smd rect
			(at -0.2667 0 90)
			(size 0.3048 0.381)
			(layers "F.Cu" "F.Mask" "F.Paste")
			(net "P5E_CPU0_G3_TX_C_DP<11>")
		)
		(pad "2" smd rect
			(at 0.2667 0 90)
			(size 0.3048 0.381)
			(layers "F.Cu" "F.Mask" "F.Paste")
			(net "P5E_CPU0_G3_TX_DP<11>")
		)
	)
	(footprint ""
		(layer "F.Cu")
		(at 111.252 -415.036 180)
		(property "Reference" "L1"
			(at 0 0 180)
			(layer "F.SilkS")
			(hide yes)
			(effects
				(font
					(size 1.27 1.27)
				)
			)
		)
		(property "Value" ""
			(at 0 0 180)
			(layer "F.Fab")
			(effects
				(font
					(size 1.27 1.27)
				)
			)
		)
		(duplicate_pad_numbers_are_jumpers no)
		(fp_line
			(start 1.63576 0.8128)
			(end -1.63576 0.8128)
			(stroke
				(width 0.1524)
				(type default)
			)
			(layer "F.SilkS")
		)
		(fp_line
			(start 1.63576 -0.8128)
			(end 1.63576 0.8128)
			(stroke
				(width 0.1524)
				(type default)
			)
			(layer "F.SilkS")
		)
		(fp_line
			(start -1.63576 -0.8128)
			(end 1.63576 -0.8128)
			(stroke
				(width 0.1524)
				(type default)
			)
			(layer "F.SilkS")
		)
		(fp_line
			(start -1.63576 -0.8128)
			(end -1.63576 0.8128)
			(stroke
				(width 0.1524)
				(type default)
			)
			(layer "F.SilkS")
		)
		(fp_line
			(start 1.560576 0.7366)
			(end 1.560576 -0.738632)
			(stroke
				(width 0.1)
				(type default)
			)
			(layer "F.Fab")
		)
		(fp_line
			(start 1.560576 -0.738632)
			(end -1.56083 -0.738632)
			(stroke
				(width 0.1)
				(type default)
			)
			(layer "F.Fab")
		)
		(fp_line
			(start 1.524 0.7366)
			(end 1.560576 0.7366)
			(stroke
				(width 0.1)
				(type default)
			)
			(layer "F.Fab")
		)
		(fp_line
			(start -1.524 0.7366)
			(end 1.524 0.7366)
			(stroke
				(width 0.1)
				(type default)
			)
			(layer "F.Fab")
		)
		(fp_line
			(start -1.56083 0.7366)
			(end -1.524 0.7366)
			(stroke
				(width 0.1)
				(type default)
			)
			(layer "F.Fab")
		)
		(fp_line
			(start -1.56083 -0.738632)
			(end -1.56083 0.7366)
			(stroke
				(width 0.1)
				(type default)
			)
			(layer "F.Fab")
		)
		(pad "1" smd rect
			(at -0.94996 0)
			(size 1.1176 1.3716)
			(layers "F.Cu" "F.Mask" "F.Paste")
			(net "P3V3_AUX")
		)
		(pad "2" smd rect
			(at 0.94996 0)
			(size 1.1176 1.3716)
			(layers "F.Cu" "F.Mask" "F.Paste")
			(net "P3V3_9ZXL045_P1")
		)
	)
)
